(kicad_pcb
	(version 20221018)
	(generator pcbnew)
	(general
    (thickness 1.656)
  )
	(paper "A4")
	(title_block
    (title "SDI-MIPI Bridge")
    (date "2023-08-09")
    (rev "1.3.4")
    (company "Antmicro")
		(comment 9 "footprints 112-122 of 190")
	)
	(layers
    (0 "F.Cu" signal)
    (1 "In1.Cu" power)
    (2 "In2.Cu" power)
    (3 "In3.Cu" signal)
    (4 "In4.Cu" signal)
    (31 "B.Cu" signal)
    (32 "B.Adhes" user "B.Adhesive")
    (33 "F.Adhes" user "F.Adhesive")
    (34 "B.Paste" user)
    (35 "F.Paste" user)
    (36 "B.SilkS" user "B.Silkscreen")
    (37 "F.SilkS" user "F.Silkscreen")
    (38 "B.Mask" user)
    (39 "F.Mask" user)
    (40 "Dwgs.User" user "User.Drawings")
    (41 "Cmts.User" user "User.Comments")
    (42 "Eco1.User" user "User.Eco1")
    (43 "Eco2.User" user "User.Eco2")
    (44 "Edge.Cuts" user)
    (45 "Margin" user)
    (46 "B.CrtYd" user "B.Courtyard")
    (47 "F.CrtYd" user "F.Courtyard")
    (48 "B.Fab" user)
    (49 "F.Fab" user)
  )
	(footprint "sdi-mipi-bridge-footprints:C_0402_1005Metric" (layer "B.Cu")
    (at 149.02 116.9 -90)
    (descr "Capacitor SMD 0402")
    (tags "capacitor SMD 0402")
    (property "Author" "Antmicro")
    (property "Dielectric" "")
    (property "License" "Apache-2.0")
    (property "MPN" "GRM155R61A475MEAAD")
    (property "Manufacturer" "Murata")
    (property "Sheetfile" "sdi-mipi-bridge.kicad_sch")
    (property "Sheetname" "")
    (property "Val" "4u7")
    (property "Voltage" "")
    (property "ki_description" " ")
    (attr smd)
    (fp_text reference "C52" (at 6.7 -9.18 90) (layer "B.SilkS")
        (effects (font (size 0.7 0.7) (thickness 0.15)) (justify left bottom mirror))
    )
    (fp_text value "C_4u7_0402" (at 0 -1.4 90) (layer "B.Fab") hide
        (effects (font (size 0.7 0.7) (thickness 0.15)) (justify left bottom mirror))
    )
    (fp_text user "License: Apache-2.0" (at -0.932 -5.17 90) (layer "B.Fab") hide
        (effects (font (size 0.7 0.7) (thickness 0.15)) (justify left bottom mirror))
    )
    (fp_text user "Author: Antmicro" (at -0.932 -4.17 90) (layer "B.Fab") hide
        (effects (font (size 0.7 0.7) (thickness 0.15)) (justify left bottom mirror))
    )
    (fp_text user "${REFERENCE}" (at -0.932 -3.168 90) (layer "B.Fab") hide
        (effects (font (size 0.7 0.7) (thickness 0.15)) (justify left bottom mirror))
    )
    (fp_rect (start -0.94 0.47) (end 0.94 -0.47)
      (stroke (width 0.05) (type solid)) (fill none) (layer "B.CrtYd"))
    (fp_rect (start -0.499 0.249) (end 0.499 -0.249)
      (stroke (width 0.15) (type solid)) (fill none) (layer "B.Fab"))
    (pad "1" smd roundrect (at -0.484 0 270) (size 0.59 0.64) (layers "B.Cu" "B.Paste" "B.Mask") (roundrect_rratio 0.25)
      (net 1 "GNDREF") (pintype "passive"))
    (pad "2" smd roundrect (at 0.484 0 270) (size 0.59 0.64) (layers "B.Cu" "B.Paste" "B.Mask") (roundrect_rratio 0.25)
      (net 2 "+1V2") (pintype "passive"))
  )
	(footprint "sdi-mipi-bridge-footprints:C_0402_1005Metric" (layer "B.Cu")
    (at 142.14 116.28 90)
    (descr "Capacitor SMD 0402")
    (tags "capacitor SMD 0402")
    (property "Author" "Antmicro")
    (property "Dielectric" "")
    (property "License" "Apache-2.0")
    (property "MPN" "C1005X6S1A105K050BC")
    (property "Manufacturer" "TDK")
    (property "Sheetfile" "sdi-mipi-bridge.kicad_sch")
    (property "Sheetname" "")
    (property "Val" "1u")
    (property "Voltage" "")
    (property "ki_description" " ")
    (attr smd)
    (fp_text reference "C47" (at -8.72 9.26 90) (layer "B.SilkS")
        (effects (font (size 0.7 0.7) (thickness 0.15)) (justify right bottom mirror))
    )
    (fp_text value "C_1u_0402" (at 0 -1.4 90) (layer "B.Fab") hide
        (effects (font (size 0.7 0.7) (thickness 0.15)) (justify right bottom mirror))
    )
    (fp_text user "License: Apache-2.0" (at -0.932 -5.17 90) (layer "B.Fab") hide
        (effects (font (size 0.7 0.7) (thickness 0.15)) (justify right bottom mirror))
    )
    (fp_text user "${REFERENCE}" (at -0.932 -3.168 90) (layer "B.Fab") hide
        (effects (font (size 0.7 0.7) (thickness 0.15)) (justify right bottom mirror))
    )
    (fp_text user "Author: Antmicro" (at -0.932 -4.17 90) (layer "B.Fab") hide
        (effects (font (size 0.7 0.7) (thickness 0.15)) (justify right bottom mirror))
    )
    (fp_rect (start -0.94 0.47) (end 0.94 -0.47)
      (stroke (width 0.05) (type solid)) (fill none) (layer "B.CrtYd"))
    (fp_rect (start -0.499 0.249) (end 0.499 -0.249)
      (stroke (width 0.15) (type solid)) (fill none) (layer "B.Fab"))
    (pad "1" smd roundrect (at -0.484 0 90) (size 0.59 0.64) (layers "B.Cu" "B.Paste" "B.Mask") (roundrect_rratio 0.25)
      (net 59 "/GNDGPLL") (pintype "passive"))
    (pad "2" smd roundrect (at 0.484 0 90) (size 0.59 0.64) (layers "B.Cu" "B.Paste" "B.Mask") (roundrect_rratio 0.25)
      (net 89 "VCCGPLL") (pintype "passive"))
  )
	(footprint "sdi-mipi-bridge-footprints:C_0402_1005Metric" (layer "B.Cu")
    (at 141.14 116.28 90)
    (descr "Capacitor SMD 0402")
    (tags "capacitor SMD 0402")
    (property "Author" "Antmicro")
    (property "Dielectric" "")
    (property "License" "Apache-2.0")
    (property "MPN" "0402X104K6R3CT")
    (property "Manufacturer" "Walsin")
    (property "Sheetfile" "sdi-mipi-bridge.kicad_sch")
    (property "Sheetname" "")
    (property "Val" "100n")
    (property "Voltage" "")
    (property "ki_description" " ")
    (attr smd)
    (fp_text reference "C51" (at -8.72 9.26 90) (layer "B.SilkS")
        (effects (font (size 0.7 0.7) (thickness 0.15)) (justify right bottom mirror))
    )
    (fp_text value "C_100n_6V3_0402" (at 0 -1.4 90) (layer "B.Fab") hide
        (effects (font (size 0.7 0.7) (thickness 0.15)) (justify right bottom mirror))
    )
    (fp_text user "Author: Antmicro" (at -0.932 -4.17 90) (layer "B.Fab") hide
        (effects (font (size 0.7 0.7) (thickness 0.15)) (justify right bottom mirror))
    )
    (fp_text user "License: Apache-2.0" (at -0.932 -5.17 90) (layer "B.Fab") hide
        (effects (font (size 0.7 0.7) (thickness 0.15)) (justify right bottom mirror))
    )
    (fp_text user "${REFERENCE}" (at -0.932 -3.168 90) (layer "B.Fab") hide
        (effects (font (size 0.7 0.7) (thickness 0.15)) (justify right bottom mirror))
    )
    (fp_rect (start -0.94 0.47) (end 0.94 -0.47)
      (stroke (width 0.05) (type solid)) (fill none) (layer "B.CrtYd"))
    (fp_rect (start -0.499 0.249) (end 0.499 -0.249)
      (stroke (width 0.15) (type solid)) (fill none) (layer "B.Fab"))
    (pad "1" smd roundrect (at -0.484 0 90) (size 0.59 0.64) (layers "B.Cu" "B.Paste" "B.Mask") (roundrect_rratio 0.25)
      (net 59 "/GNDGPLL") (pintype "passive"))
    (pad "2" smd roundrect (at 0.484 0 90) (size 0.59 0.64) (layers "B.Cu" "B.Paste" "B.Mask") (roundrect_rratio 0.25)
      (net 89 "VCCGPLL") (pintype "passive"))
  )
	(footprint "sdi-mipi-bridge-footprints:FB_0603_1608Metric" (layer "B.Cu")
    (at 147.505 109.6)
    (property "Author" "Antmicro")
    (property "License" "Apache-2.0")
    (property "MPN" "BLM18PG121SN1D")
    (property "Manufacturer" "Murata")
    (property "Sheetfile" "sdi-mipi-bridge.kicad_sch")
    (property "Sheetname" "")
    (property "ki_description" "Ferrite Beads WE-TMSB Suppression 240Ohm 200mA ")
    (property "ki_keywords" " Multilayer Suppression Beads ")
    (attr smd)
    (fp_text reference "FB2" (at 1.095 1.6 180) (layer "B.SilkS")
        (effects (font (size 0.7 0.7) (thickness 0.15)) (justify left bottom mirror))
    )
    (fp_text value "BLM18PG121SH1D" (at 0 -1.5 180) (layer "B.Fab") hide
        (effects (font (size 0.7 0.7) (thickness 0.15)) (justify left bottom mirror))
    )
    (fp_text user "${REFERENCE}" (at -1.653 -4.6 180) (layer "B.Fab") hide
        (effects (font (size 0.7 0.7) (thickness 0.15)) (justify left bottom mirror))
    )
    (fp_text user "Author: Antmicro" (at -1.653 -3.162 180) (layer "B.Fab") hide
        (effects (font (size 0.7 0.7) (thickness 0.15)) (justify left bottom mirror))
    )
    (fp_text user "License: Apache-2.0" (at -1.653 -5.9 180) (layer "B.Fab") hide
        (effects (font (size 0.7 0.7) (thickness 0.15)) (justify left bottom mirror))
    )
    (fp_line (start -0.196 -0.406) (end 0.193 -0.406)
      (stroke (width 0.15) (type solid)) (layer "B.SilkS"))
    (fp_line (start -0.196 0.408) (end 0.193 0.408)
      (stroke (width 0.15) (type solid)) (layer "B.SilkS"))
    (fp_rect (start -1.3 0.6) (end 1.3 -0.6)
      (stroke (width 0.05) (type solid)) (fill none) (layer "B.CrtYd"))
    (fp_line (start -0.803 -0.406) (end -0.803 0.408)
      (stroke (width 0.15) (type solid)) (layer "B.Fab"))
    (fp_line (start 0.8 -0.406) (end -0.803 -0.406)
      (stroke (width 0.15) (type solid)) (layer "B.Fab"))
    (fp_line (start 0.8 0.408) (end -0.803 0.408)
      (stroke (width 0.15) (type solid)) (layer "B.Fab"))
    (fp_line (start 0.8 0.408) (end 0.8 -0.406)
      (stroke (width 0.15) (type solid)) (layer "B.Fab"))
    (pad "1" smd roundrect (at -0.891 0) (size 0.762 1.09) (layers "B.Cu" "B.Paste" "B.Mask") (roundrect_rratio 0.15)
      (net 2 "+1V2") (pintype "passive"))
    (pad "2" smd roundrect (at 0.888 0) (size 0.762 1.09) (layers "B.Cu" "B.Paste" "B.Mask") (roundrect_rratio 0.15)
      (net 77 "VCCA_DPHY") (pintype "passive"))
  )
	(footprint "sdi-mipi-bridge-footprints:FB_0603_1608Metric" (layer "B.Cu")
    (at 141.65 118.6 -90)
    (property "Author" "Antmicro")
    (property "License" "Apache-2.0")
    (property "MPN" "BLM18PG121SN1D")
    (property "Manufacturer" "Murata")
    (property "Sheetfile" "sdi-mipi-bridge.kicad_sch")
    (property "Sheetname" "")
    (property "ki_description" "Ferrite Beads WE-TMSB Suppression 240Ohm 200mA ")
    (property "ki_keywords" " Multilayer Suppression Beads ")
    (attr smd)
    (fp_text reference "FB3" (at 6.8 -9.15 90) (layer "B.SilkS")
        (effects (font (size 0.7 0.7) (thickness 0.15)) (justify left bottom mirror))
    )
    (fp_text value "BLM18PG121SH1D" (at 0 -1.5 90) (layer "B.Fab") hide
        (effects (font (size 0.7 0.7) (thickness 0.15)) (justify left bottom mirror))
    )
    (fp_text user "License: Apache-2.0" (at -1.653 -5.9 90) (layer "B.Fab") hide
        (effects (font (size 0.7 0.7) (thickness 0.15)) (justify left bottom mirror))
    )
    (fp_text user "${REFERENCE}" (at -1.653 -4.6 90) (layer "B.Fab") hide
        (effects (font (size 0.7 0.7) (thickness 0.15)) (justify left bottom mirror))
    )
    (fp_text user "Author: Antmicro" (at -1.653 -3.162 90) (layer "B.Fab") hide
        (effects (font (size 0.7 0.7) (thickness 0.15)) (justify left bottom mirror))
    )
    (fp_line (start -0.196 -0.406) (end 0.193 -0.406)
      (stroke (width 0.15) (type solid)) (layer "B.SilkS"))
    (fp_line (start -0.196 0.408) (end 0.193 0.408)
      (stroke (width 0.15) (type solid)) (layer "B.SilkS"))
    (fp_rect (start -1.3 0.6) (end 1.3 -0.6)
      (stroke (width 0.05) (type solid)) (fill none) (layer "B.CrtYd"))
    (fp_line (start -0.803 -0.406) (end -0.803 0.408)
      (stroke (width 0.15) (type solid)) (layer "B.Fab"))
    (fp_line (start 0.8 -0.406) (end -0.803 -0.406)
      (stroke (width 0.15) (type solid)) (layer "B.Fab"))
    (fp_line (start 0.8 0.408) (end -0.803 0.408)
      (stroke (width 0.15) (type solid)) (layer "B.Fab"))
    (fp_line (start 0.8 0.408) (end 0.8 -0.406)
      (stroke (width 0.15) (type solid)) (layer "B.Fab"))
    (pad "1" smd roundrect (at -0.891 0 270) (size 0.762 1.09) (layers "B.Cu" "B.Paste" "B.Mask") (roundrect_rratio 0.15)
      (net 89 "VCCGPLL") (pintype "passive"))
    (pad "2" smd roundrect (at 0.888 0 270) (size 0.762 1.09) (layers "B.Cu" "B.Paste" "B.Mask") (roundrect_rratio 0.15)
      (net 2 "+1V2") (pintype "passive"))
  )
	(footprint "sdi-mipi-bridge-footprints:R_0402_1005Metric" (layer "B.Cu")
    (at 148.98 114.94 90)
    (descr "Resistor SMD 0402")
    (tags "resistor SMD 0402")
    (property "Author" "Antmicro")
    (property "Current" "1A")
    (property "License" "Apache-2.0")
    (property "MPN" "ERJ2GE0R00X")
    (property "Manufacturer" "Panasonic")
    (property "Sheetfile" "sdi-mipi-bridge.kicad_sch")
    (property "Sheetname" "")
    (property "Tolerance" "")
    (property "Val" "0R")
    (property "ki_description" "0R resistor in 0402 package with unspecified tolerance")
    (attr smd)
    (fp_text reference "R26" (at -8.86 9.22 90) (layer "B.SilkS")
        (effects (font (size 0.7 0.7) (thickness 0.15)) (justify right bottom mirror))
    )
    (fp_text value "R_0R_0402" (at 0 -1.4 90) (layer "B.Fab") hide
        (effects (font (size 0.7 0.7) (thickness 0.15)) (justify right bottom mirror))
    )
    (fp_text user "License: Apache-2.0" (at -0.95 -5.169 90) (layer "B.Fab") hide
        (effects (font (size 0.7 0.7) (thickness 0.15)) (justify right bottom mirror))
    )
    (fp_text user "Author: Antmicro" (at -0.95 -4.169 90) (layer "B.Fab") hide
        (effects (font (size 0.7 0.7) (thickness 0.15)) (justify right bottom mirror))
    )
    (fp_text user "${REFERENCE}" (at -0.95 -3.168 90) (layer "B.Fab") hide
        (effects (font (size 0.7 0.7) (thickness 0.15)) (justify right bottom mirror))
    )
    (fp_rect (start -0.93 0.47) (end 0.93 -0.47)
      (stroke (width 0.05) (type solid)) (fill none) (layer "B.CrtYd"))
    (fp_rect (start -0.5 0.25) (end 0.5 -0.25)
      (stroke (width 0.15) (type solid)) (fill none) (layer "B.Fab"))
    (pad "1" smd roundrect (at -0.485 0 90) (size 0.59 0.64) (layers "B.Cu" "B.Paste" "B.Mask") (roundrect_rratio 0.25)
      (net 6 "+3V3") (pintype "passive"))
    (pad "2" smd roundrect (at 0.485 0 90) (size 0.59 0.64) (layers "B.Cu" "B.Paste" "B.Mask") (roundrect_rratio 0.25)
      (net 141 "Net-(C45-Pad2)") (pintype "passive"))
  )
	(footprint "sdi-mipi-bridge-footprints:R_0402_1005Metric" (layer "B.Cu")
    (at 144.2825 109.525 -90)
    (descr "Resistor SMD 0402")
    (tags "resistor SMD 0402")
    (property "Author" "Antmicro")
    (property "License" "Apache-2.0")
    (property "MPN" "CR0402-FX-4701GLF")
    (property "Manufacturer" "Bourns")
    (property "Sheetfile" "sdi-mipi-bridge.kicad_sch")
    (property "Sheetname" "")
    (property "Tolerance" "1%")
    (property "Val" "4k7")
    (property "ki_description" "4k7 resistor in 0402 package with 1% tolerance")
    (attr smd)
    (fp_text reference "R35" (at -5.125 3.1825 90) (layer "B.SilkS")
        (effects (font (size 0.7 0.7) (thickness 0.15)) (justify left bottom mirror))
    )
    (fp_text value "R_4k7_0402" (at 0 -1.4 90) (layer "B.Fab") hide
        (effects (font (size 0.7 0.7) (thickness 0.15)) (justify left bottom mirror))
    )
    (fp_text user "Author: Antmicro" (at -0.95 -4.169 90) (layer "B.Fab") hide
        (effects (font (size 0.7 0.7) (thickness 0.15)) (justify left bottom mirror))
    )
    (fp_text user "License: Apache-2.0" (at -0.95 -5.169 90) (layer "B.Fab") hide
        (effects (font (size 0.7 0.7) (thickness 0.15)) (justify left bottom mirror))
    )
    (fp_text user "${REFERENCE}" (at -0.95 -3.168 90) (layer "B.Fab") hide
        (effects (font (size 0.7 0.7) (thickness 0.15)) (justify left bottom mirror))
    )
    (fp_rect (start -0.93 0.47) (end 0.93 -0.47)
      (stroke (width 0.05) (type solid)) (fill none) (layer "B.CrtYd"))
    (fp_rect (start -0.5 0.25) (end 0.5 -0.25)
      (stroke (width 0.15) (type solid)) (fill none) (layer "B.Fab"))
    (pad "1" smd roundrect (at -0.485 0 270) (size 0.59 0.64) (layers "B.Cu" "B.Paste" "B.Mask") (roundrect_rratio 0.25)
      (net 100 "/CRESET_B") (pintype "passive"))
    (pad "2" smd roundrect (at 0.485 0 270) (size 0.59 0.64) (layers "B.Cu" "B.Paste" "B.Mask") (roundrect_rratio 0.25)
      (net 79 "VCC_IO") (pintype "passive"))
  )
	(footprint "sdi-mipi-bridge-footprints:R_0402_1005Metric" (layer "B.Cu")
    (at 143.1 109.525 -90)
    (descr "Resistor SMD 0402")
    (tags "resistor SMD 0402")
    (property "Author" "Antmicro")
    (property "License" "Apache-2.0")
    (property "MPN" "CR0402-FX-4701GLF")
    (property "Manufacturer" "Bourns")
    (property "Sheetfile" "sdi-mipi-bridge.kicad_sch")
    (property "Sheetname" "")
    (property "Tolerance" "1%")
    (property "Val" "4k7")
    (property "ki_description" "4k7 resistor in 0402 package with 1% tolerance")
    (attr smd)
    (fp_text reference "R36" (at -5.124 3.0175 90) (layer "B.SilkS")
        (effects (font (size 0.7 0.7) (thickness 0.15)) (justify left bottom mirror))
    )
    (fp_text value "R_4k7_0402" (at 0 -1.4 90) (layer "B.Fab") hide
        (effects (font (size 0.7 0.7) (thickness 0.15)) (justify left bottom mirror))
    )
    (fp_text user "${REFERENCE}" (at -0.95 -3.168 90) (layer "B.Fab") hide
        (effects (font (size 0.7 0.7) (thickness 0.15)) (justify left bottom mirror))
    )
    (fp_text user "License: Apache-2.0" (at -0.95 -5.169 90) (layer "B.Fab") hide
        (effects (font (size 0.7 0.7) (thickness 0.15)) (justify left bottom mirror))
    )
    (fp_text user "Author: Antmicro" (at -0.95 -4.169 90) (layer "B.Fab") hide
        (effects (font (size 0.7 0.7) (thickness 0.15)) (justify left bottom mirror))
    )
    (fp_rect (start -0.93 0.47) (end 0.93 -0.47)
      (stroke (width 0.05) (type solid)) (fill none) (layer "B.CrtYd"))
    (fp_rect (start -0.5 0.25) (end 0.5 -0.25)
      (stroke (width 0.15) (type solid)) (fill none) (layer "B.Fab"))
    (pad "1" smd roundrect (at -0.485 0 270) (size 0.59 0.64) (layers "B.Cu" "B.Paste" "B.Mask") (roundrect_rratio 0.25)
      (net 88 "/CDONE") (pintype "passive"))
    (pad "2" smd roundrect (at 0.485 0 270) (size 0.59 0.64) (layers "B.Cu" "B.Paste" "B.Mask") (roundrect_rratio 0.25)
      (net 79 "VCC_IO") (pintype "passive"))
  )
	(footprint "sdi-mipi-bridge-footprints:TP_SMD_0.75mm" (layer "B.Cu")
    (at 130.9492 122.4 90)
    (property "Author" "Antmicro")
    (property "License" "Apache-2.0")
    (property "MPN" "")
    (property "Manufacturer" "")
    (property "Sheetfile" "sdi-mipi-bridge.kicad_sch")
    (property "Sheetname" "")
    (property "ki_description" "Test Point 0.75mm")
    (attr smd)
    (fp_text reference "TP7" (at -0.4 -0.5492 180) (layer "B.SilkS")
        (effects (font (size 0.7 0.7) (thickness 0.15)) (justify left bottom mirror))
    )
    (fp_text value "TP_0.75mm_SMD" (at 0 -1.2 90) (layer "B.Fab") hide
        (effects (font (size 0.7 0.7) (thickness 0.15)) (justify right bottom mirror))
    )
    (fp_text user "Author: Antmicro" (at -0.4 -3.901 90) (layer "B.Fab") hide
        (effects (font (size 0.7 0.7) (thickness 0.15)) (justify right bottom mirror))
    )
    (fp_text user "${REFERENCE}" (at -0.4 -2.7 90) (layer "B.Fab") hide
        (effects (font (size 0.7 0.7) (thickness 0.15)) (justify right bottom mirror))
    )
    (fp_text user "License: Apache-2.0" (at -0.4 -5.101 90) (layer "B.Fab") hide
        (effects (font (size 0.7 0.7) (thickness 0.15)) (justify right bottom mirror))
    )
    (pad "1" smd circle (at 0 0 90) (size 0.75 0.75) (layers "B.Cu" "B.Mask")
      (net 30 "/D0") (pinfunction "1") (pintype "passive"))
  )
	(footprint "sdi-mipi-bridge-footprints:TP_SMD_0.75mm" (layer "B.Cu")
    (at 130.9492 121.4 90)
    (property "Author" "Antmicro")
    (property "License" "Apache-2.0")
    (property "MPN" "")
    (property "Manufacturer" "")
    (property "Sheetfile" "sdi-mipi-bridge.kicad_sch")
    (property "Sheetname" "")
    (property "ki_description" "Test Point 0.75mm")
    (attr smd)
    (fp_text reference "TP8" (at -0.4 0.6508 180) (layer "B.SilkS")
        (effects (font (size 0.7 0.7) (thickness 0.15)) (justify right bottom mirror))
    )
    (fp_text value "TP_0.75mm_SMD" (at 0 -1.2 90) (layer "B.Fab") hide
        (effects (font (size 0.7 0.7) (thickness 0.15)) (justify right bottom mirror))
    )
    (fp_text user "License: Apache-2.0" (at -0.4 -5.101 90) (layer "B.Fab") hide
        (effects (font (size 0.7 0.7) (thickness 0.15)) (justify right bottom mirror))
    )
    (fp_text user "${REFERENCE}" (at -0.4 -2.7 90) (layer "B.Fab") hide
        (effects (font (size 0.7 0.7) (thickness 0.15)) (justify right bottom mirror))
    )
    (fp_text user "Author: Antmicro" (at -0.4 -3.901 90) (layer "B.Fab") hide
        (effects (font (size 0.7 0.7) (thickness 0.15)) (justify right bottom mirror))
    )
    (pad "1" smd circle (at 0 0 90) (size 0.75 0.75) (layers "B.Cu" "B.Mask")
      (net 31 "/D1") (pinfunction "1") (pintype "passive"))
  )
	(footprint "sdi-mipi-bridge-footprints:TP_SMD_0.75mm" (layer "B.Cu")
    (at 130.9492 120.4 90)
    (property "Author" "Antmicro")
    (property "License" "Apache-2.0")
    (property "MPN" "")
    (property "Manufacturer" "")
    (property "Sheetfile" "sdi-mipi-bridge.kicad_sch")
    (property "Sheetname" "")
    (property "ki_description" "Test Point 0.75mm")
    (attr smd)
    (fp_text reference "TP9" (at -0.4 0.6508 180) (layer "B.SilkS")
        (effects (font (size 0.7 0.7) (thickness 0.15)) (justify right bottom mirror))
    )
    (fp_text value "TP_0.75mm_SMD" (at 0 -1.2 90) (layer "B.Fab") hide
        (effects (font (size 0.7 0.7) (thickness 0.15)) (justify right bottom mirror))
    )
    (fp_text user "${REFERENCE}" (at -0.4 -2.7 90) (layer "B.Fab") hide
        (effects (font (size 0.7 0.7) (thickness 0.15)) (justify right bottom mirror))
    )
    (fp_text user "Author: Antmicro" (at -0.4 -3.901 90) (layer "B.Fab") hide
        (effects (font (size 0.7 0.7) (thickness 0.15)) (justify right bottom mirror))
    )
    (fp_text user "License: Apache-2.0" (at -0.4 -5.101 90) (layer "B.Fab") hide
        (effects (font (size 0.7 0.7) (thickness 0.15)) (justify right bottom mirror))
    )
    (pad "1" smd circle (at 0 0 90) (size 0.75 0.75) (layers "B.Cu" "B.Mask")
      (net 32 "/D2") (pinfunction "1") (pintype "passive"))
  )
)
